FILE_TYPE = CONNECTIVITY;
{Allegro Design Entry HDL 16.6-p007 (v16-6-112F) 10/10/2012}
"PAGE_NUMBER" = 180;
0"NC";
END.
